(kicad_pcb
	(version 20241229)
	(generator "pcbnew")
	(generator_version "9.0")
	(general
		(thickness 1.6296)
		(legacy_teardrops no)
	)
	(paper "A3")
	(title_block
		(title "Thunderbolt to 10GbE adapter")
		(date "2026-04-21")
		(rev "1.1.0")
		(company "Antmicro Ltd")
		(comment 1 "www.antmicro.com")
		(comment 9 "footprints 393-396 of 703")
	)
	(layers
		(0 "F.Cu" signal)
		(4 "In1.Cu" signal)
		(6 "In2.Cu" signal)
		(8 "In3.Cu" signal)
		(10 "In4.Cu" signal)
		(12 "In5.Cu" signal)
		(14 "In6.Cu" signal)
		(2 "B.Cu" signal)
		(9 "F.Adhes" user "F.Adhesive")
		(11 "B.Adhes" user "B.Adhesive")
		(13 "F.Paste" user)
		(15 "B.Paste" user)
		(5 "F.SilkS" user "F.Silkscreen")
		(7 "B.SilkS" user "B.Silkscreen")
		(1 "F.Mask" user)
		(3 "B.Mask" user)
		(17 "Dwgs.User" user "User.Drawings")
		(19 "Cmts.User" user "User.Comments")
		(21 "Eco1.User" user "User.Eco1")
		(23 "Eco2.User" user "User.Eco2")
		(25 "Edge.Cuts" user)
		(27 "Margin" user)
		(31 "F.CrtYd" user "F.Courtyard")
		(29 "B.CrtYd" user "B.Courtyard")
		(35 "F.Fab" user)
		(33 "B.Fab" user)
	)
	(footprint "antmicro-footprints:C_Pol_EIA-A"
		(layer "B.Cu")
		(at 141 103.7 -90)
		(property "Reference" "C331"
			(at 2.2 -0.4 90)
			(layer "B.SilkS")
			(effects
				(font
					(size 0.7 0.7)
					(thickness 0.15)
				)
				(justify left bottom mirror)
			)
		)
		(property "Value" "C_Pol_100u_6V_KEMET-T490-A"
			(at 0 -2 90)
			(layer "B.Fab")
			(effects
				(font
					(size 0.7 0.7)
					(thickness 0.15)
				)
				(justify left bottom mirror)
			)
		)
		(property "Datasheet" "https://www.kemet.com/en/us/capacitors/product/T490A107M006ATE800.html"
			(at 0 0 90)
			(layer "B.Fab")
			(hide yes)
			(effects
				(font
					(size 1.27 1.27)
					(thickness 0.15)
				)
				(justify mirror)
			)
		)
		(property "Description" "Surface Mount Tantalum Capacitor,  Solid SMD 6V 100uF 1206 20% ESR=800mOhms"
			(at 0 0 90)
			(layer "B.Fab")
			(hide yes)
			(effects
				(font
					(size 1.27 1.27)
					(thickness 0.15)
				)
				(justify mirror)
			)
		)
		(property "Val" "100u"
			(at 0 0 270)
			(unlocked yes)
			(layer "B.Fab")
			(hide yes)
			(effects
				(font
					(size 1 1)
					(thickness 0.15)
				)
				(justify mirror)
			)
		)
		(property "MPN" "T490A107M006ATE800"
			(at 0 0 270)
			(unlocked yes)
			(layer "B.Fab")
			(hide yes)
			(effects
				(font
					(size 1 1)
					(thickness 0.15)
				)
				(justify mirror)
			)
		)
		(property "Manufacturer" "KEMET"
			(at 0 0 270)
			(unlocked yes)
			(layer "B.Fab")
			(hide yes)
			(effects
				(font
					(size 1 1)
					(thickness 0.15)
				)
				(justify mirror)
			)
		)
		(property "License" "Apache-2.0"
			(at 0 0 270)
			(unlocked yes)
			(layer "B.Fab")
			(hide yes)
			(effects
				(font
					(size 1 1)
					(thickness 0.15)
				)
				(justify mirror)
			)
		)
		(property "Author" "Antmicro"
			(at 0 0 270)
			(unlocked yes)
			(layer "B.Fab")
			(hide yes)
			(effects
				(font
					(size 1 1)
					(thickness 0.15)
				)
				(justify mirror)
			)
		)
		(property "Voltage" "6V"
			(at 0 0 270)
			(unlocked yes)
			(layer "B.Fab")
			(hide yes)
			(effects
				(font
					(size 1 1)
					(thickness 0.15)
				)
				(justify mirror)
			)
		)
		(property "Dielectric" "template_dielectric"
			(at 0 0 270)
			(unlocked yes)
			(layer "B.Fab")
			(hide yes)
			(effects
				(font
					(size 1 1)
					(thickness 0.15)
				)
				(justify mirror)
			)
		)
		(sheetname "/X710-AT2 power/")
		(sheetfile "x710-at2-power.kicad_sch")
		(attr smd)
		(fp_line
			(start -1.95 1.25)
			(end -1.95 0.95)
			(stroke
				(width 0.12)
				(type solid)
			)
			(layer "B.SilkS")
		)
		(fp_line
			(start -2.1 1.1)
			(end -1.8 1.1)
			(stroke
				(width 0.12)
				(type solid)
			)
			(layer "B.SilkS")
		)
		(fp_line
			(start -1.5 0.85)
			(end 1.5 0.85)
			(stroke
				(width 0.12)
				(type solid)
			)
			(layer "B.SilkS")
		)
		(fp_line
			(start -1.5 0.75)
			(end -1.5 0.85)
			(stroke
				(width 0.12)
				(type solid)
			)
			(layer "B.SilkS")
		)
		(fp_line
			(start 1.5 0.75)
			(end 1.5 0.85)
			(stroke
				(width 0.12)
				(type solid)
			)
			(layer "B.SilkS")
		)
		(fp_line
			(start -1.5 -0.75)
			(end -1.5 -0.85)
			(stroke
				(width 0.12)
				(type solid)
			)
			(layer "B.SilkS")
		)
		(fp_line
			(start 1.5 -0.75)
			(end 1.5 -0.85)
			(stroke
				(width 0.12)
				(type solid)
			)
			(layer "B.SilkS")
		)
		(fp_line
			(start 1.5 -0.85)
			(end -1.5 -0.85)
			(stroke
				(width 0.12)
				(type solid)
			)
			(layer "B.SilkS")
		)
		(fp_line
			(start 1.7 1.05)
			(end -1.7 1.05)
			(stroke
				(width 0.05)
				(type solid)
			)
			(layer "B.CrtYd")
		)
		(fp_line
			(start -2.05 0.85)
			(end -2.05 -0.85)
			(stroke
				(width 0.05)
				(type solid)
			)
			(layer "B.CrtYd")
		)
		(fp_line
			(start -1.7 0.85)
			(end -1.7 1.05)
			(stroke
				(width 0.05)
				(type solid)
			)
			(layer "B.CrtYd")
		)
		(fp_line
			(start -1.7 0.85)
			(end -2.05 0.85)
			(stroke
				(width 0.05)
				(type solid)
			)
			(layer "B.CrtYd")
		)
		(fp_line
			(start 1.7 0.85)
			(end 1.7 1.05)
			(stroke
				(width 0.05)
				(type solid)
			)
			(layer "B.CrtYd")
		)
		(fp_line
			(start 2.05 0.85)
			(end 1.7 0.85)
			(stroke
				(width 0.05)
				(type solid)
			)
			(layer "B.CrtYd")
		)
		(fp_line
			(start 2.05 0.85)
			(end 2.05 -0.85)
			(stroke
				(width 0.05)
				(type solid)
			)
			(layer "B.CrtYd")
		)
		(fp_line
			(start -1.7 -0.85)
			(end -2.05 -0.85)
			(stroke
				(width 0.05)
				(type solid)
			)
			(layer "B.CrtYd")
		)
		(fp_line
			(start 2.05 -0.85)
			(end 1.7 -0.85)
			(stroke
				(width 0.05)
				(type solid)
			)
			(layer "B.CrtYd")
		)
		(fp_line
			(start -1.7 -1.05)
			(end -1.7 -0.85)
			(stroke
				(width 0.05)
				(type solid)
			)
			(layer "B.CrtYd")
		)
		(fp_line
			(start 1.7 -1.05)
			(end 1.7 -0.85)
			(stroke
				(width 0.05)
				(type solid)
			)
			(layer "B.CrtYd")
		)
		(fp_line
			(start 1.7 -1.05)
			(end -1.7 -1.05)
			(stroke
				(width 0.05)
				(type solid)
			)
			(layer "B.CrtYd")
		)
		(fp_rect
			(start -1.601 0.802)
			(end 1.6 -0.8)
			(stroke
				(width 0.1)
				(type solid)
			)
			(fill no)
			(layer "B.Fab")
		)
		(fp_text user "License: Apache-2.0"
			(at -2.1 -5.198 90)
			(layer "B.Fab")
			(effects
				(font
					(size 0.7 0.7)
					(thickness 0.15)
				)
				(justify left bottom mirror)
			)
		)
		(fp_text user "Author: Antmicro"
			(at -2.1 -6.198 90)
			(layer "B.Fab")
			(effects
				(font
					(size 0.7 0.7)
					(thickness 0.15)
				)
				(justify left bottom mirror)
			)
		)
		(fp_text user "${REFERENCE}"
			(at -2.1 -4.198 90)
			(layer "B.Fab")
			(effects
				(font
					(size 0.7 0.7)
					(thickness 0.15)
				)
				(justify left bottom mirror)
			)
		)
		(pad "1" smd roundrect
			(at -1.2 0 270)
			(size 1.2 1.2)
			(layers "B.Cu" "B.Mask" "B.Paste")
			(roundrect_rratio 0.1)
			(net 6 "DVDD")
			(pintype "passive")
		)
		(pad "2" smd roundrect
			(at 1.2 0 270)
			(size 1.2 1.2)
			(layers "B.Cu" "B.Mask" "B.Paste")
			(roundrect_rratio 0.1)
			(net 23 "GND")
			(pintype "passive")
		)
	)
	(footprint "antmicro-footprints:C_0402_1005Metric"
		(layer "B.Cu")
		(at 153.031867 79.260117 180)
		(descr "Capacitor SMD 0402")
		(tags "capacitor SMD 0402")
		(property "Reference" "C263"
			(at -21.168135 -9.464883 0)
			(layer "B.SilkS")
			(effects
				(font
					(size 0.7 0.7)
					(thickness 0.15)
				)
				(justify mirror)
			)
		)
		(property "Value" "C_1u_25V_0402"
			(at -1.022927 -2.155213 0)
			(layer "B.Fab")
			(effects
				(font
					(size 0.7 0.7)
					(thickness 0.15)
				)
				(justify left bottom mirror)
			)
		)
		(property "Datasheet" "https://www.murata.com/products/productdetail?partno=GRM155R61E105KE11%23"
			(at 0 0 0)
			(layer "B.Fab")
			(hide yes)
			(effects
				(font
					(size 1.27 1.27)
					(thickness 0.15)
				)
				(justify mirror)
			)
		)
		(property "Description" "SMD Multilayer Ceramic Capacitor, 1 µF, 25 V, 0402 [1005 Metric], ± 10%, X5R, GRM Series"
			(at 0 0 0)
			(layer "B.Fab")
			(hide yes)
			(effects
				(font
					(size 1.27 1.27)
					(thickness 0.15)
				)
				(justify mirror)
			)
		)
		(property "MPN" "GRM155R61E105KE11J"
			(at 0 0 180)
			(unlocked yes)
			(layer "B.Fab")
			(hide yes)
			(effects
				(font
					(size 1 1)
					(thickness 0.15)
				)
				(justify mirror)
			)
		)
		(property "Manufacturer" "Murata"
			(at 0 0 180)
			(unlocked yes)
			(layer "B.Fab")
			(hide yes)
			(effects
				(font
					(size 1 1)
					(thickness 0.15)
				)
				(justify mirror)
			)
		)
		(property "License" "Apache-2.0"
			(at 0 0 180)
			(unlocked yes)
			(layer "B.Fab")
			(hide yes)
			(effects
				(font
					(size 1 1)
					(thickness 0.15)
				)
				(justify mirror)
			)
		)
		(property "Author" "Antmicro"
			(at 0 0 180)
			(unlocked yes)
			(layer "B.Fab")
			(hide yes)
			(effects
				(font
					(size 1 1)
					(thickness 0.15)
				)
				(justify mirror)
			)
		)
		(property "Val" "1u"
			(at 0 0 180)
			(unlocked yes)
			(layer "B.Fab")
			(hide yes)
			(effects
				(font
					(size 1 1)
					(thickness 0.15)
				)
				(justify mirror)
			)
		)
		(property "Voltage" "25V"
			(at 0 0 180)
			(unlocked yes)
			(layer "B.Fab")
			(hide yes)
			(effects
				(font
					(size 1 1)
					(thickness 0.15)
				)
				(justify mirror)
			)
		)
		(property "Dielectric" "X5R"
			(at 0 0 180)
			(unlocked yes)
			(layer "B.Fab")
			(hide yes)
			(effects
				(font
					(size 1 1)
					(thickness 0.15)
				)
				(justify mirror)
			)
		)
		(sheetname "/X710-AT2 power/")
		(sheetfile "x710-at2-power.kicad_sch")
		(attr smd)
		(fp_rect
			(start -0.925 0.47)
			(end 0.925 -0.47)
			(stroke
				(width 0.05)
				(type default)
			)
			(fill no)
			(layer "B.CrtYd")
		)
		(fp_line
			(start 0.504 0.25)
			(end 0.504 -0.248)
			(stroke
				(width 0.15)
				(type solid)
			)
			(layer "B.Fab")
		)
		(fp_line
			(start 0.504 -0.248)
			(end -0.494 -0.248)
			(stroke
				(width 0.15)
				(type solid)
			)
			(layer "B.Fab")
		)
		(fp_line
			(start -0.494 0.25)
			(end 0.504 0.25)
			(stroke
				(width 0.15)
				(type solid)
			)
			(layer "B.Fab")
		)
		(fp_line
			(start -0.494 -0.248)
			(end -0.494 0.25)
			(stroke
				(width 0.15)
				(type solid)
			)
			(layer "B.Fab")
		)
		(fp_text user "License: Apache-2.0"
			(at -0.939 -5.799 0)
			(layer "B.Fab")
			(effects
				(font
					(size 0.7 0.7)
					(thickness 0.15)
				)
				(justify left bottom mirror)
			)
		)
		(fp_text user "${REFERENCE}"
			(at -0.939 -4.599 0)
			(layer "B.Fab")
			(effects
				(font
					(size 0.7 0.7)
					(thickness 0.15)
				)
				(justify left bottom mirror)
			)
		)
		(fp_text user "Author: Antmicro"
			(at -0.939 -3.399 0)
			(layer "B.Fab")
			(effects
				(font
					(size 0.7 0.7)
					(thickness 0.15)
				)
				(justify left bottom mirror)
			)
		)
		(pad "1" smd roundrect
			(at -0.48 0 180)
			(size 0.59 0.64)
			(layers "B.Cu" "B.Mask" "B.Paste")
			(roundrect_rratio 0.25)
			(net 23 "GND")
			(pintype "passive")
		)
		(pad "2" smd roundrect
			(at 0.48 0 180)
			(size 0.59 0.64)
			(layers "B.Cu" "B.Mask" "B.Paste")
			(roundrect_rratio 0.25)
			(net 1 "VCCA")
			(pintype "passive")
		)
	)
	(footprint "antmicro-footprints:C_0402_1005Metric"
		(layer "B.Cu")
		(at 147.481866 76.260118 180)
		(descr "Capacitor SMD 0402")
		(tags "capacitor SMD 0402")
		(property "Reference" "C233"
			(at -18.618135 -9.464883 0)
			(layer "B.SilkS")
			(effects
				(font
					(size 0.7 0.7)
					(thickness 0.15)
				)
				(justify mirror)
			)
		)
		(property "Value" "C_1u_25V_0402"
			(at -1.022927 -2.155213 0)
			(layer "B.Fab")
			(effects
				(font
					(size 0.7 0.7)
					(thickness 0.15)
				)
				(justify left bottom mirror)
			)
		)
		(property "Datasheet" "https://www.murata.com/products/productdetail?partno=GRM155R61E105KE11%23"
			(at 0 0 0)
			(layer "B.Fab")
			(hide yes)
			(effects
				(font
					(size 1.27 1.27)
					(thickness 0.15)
				)
				(justify mirror)
			)
		)
		(property "Description" "SMD Multilayer Ceramic Capacitor, 1 µF, 25 V, 0402 [1005 Metric], ± 10%, X5R, GRM Series"
			(at 0 0 0)
			(layer "B.Fab")
			(hide yes)
			(effects
				(font
					(size 1.27 1.27)
					(thickness 0.15)
				)
				(justify mirror)
			)
		)
		(property "MPN" "GRM155R61E105KE11J"
			(at 0 0 180)
			(unlocked yes)
			(layer "B.Fab")
			(hide yes)
			(effects
				(font
					(size 1 1)
					(thickness 0.15)
				)
				(justify mirror)
			)
		)
		(property "Manufacturer" "Murata"
			(at 0 0 180)
			(unlocked yes)
			(layer "B.Fab")
			(hide yes)
			(effects
				(font
					(size 1 1)
					(thickness 0.15)
				)
				(justify mirror)
			)
		)
		(property "License" "Apache-2.0"
			(at 0 0 180)
			(unlocked yes)
			(layer "B.Fab")
			(hide yes)
			(effects
				(font
					(size 1 1)
					(thickness 0.15)
				)
				(justify mirror)
			)
		)
		(property "Author" "Antmicro"
			(at 0 0 180)
			(unlocked yes)
			(layer "B.Fab")
			(hide yes)
			(effects
				(font
					(size 1 1)
					(thickness 0.15)
				)
				(justify mirror)
			)
		)
		(property "Val" "1u"
			(at 0 0 180)
			(unlocked yes)
			(layer "B.Fab")
			(hide yes)
			(effects
				(font
					(size 1 1)
					(thickness 0.15)
				)
				(justify mirror)
			)
		)
		(property "Voltage" "25V"
			(at 0 0 180)
			(unlocked yes)
			(layer "B.Fab")
			(hide yes)
			(effects
				(font
					(size 1 1)
					(thickness 0.15)
				)
				(justify mirror)
			)
		)
		(property "Dielectric" "X5R"
			(at 0 0 180)
			(unlocked yes)
			(layer "B.Fab")
			(hide yes)
			(effects
				(font
					(size 1 1)
					(thickness 0.15)
				)
				(justify mirror)
			)
		)
		(sheetname "/X710-AT2 power/")
		(sheetfile "x710-at2-power.kicad_sch")
		(attr smd)
		(fp_rect
			(start -0.925 0.47)
			(end 0.925 -0.47)
			(stroke
				(width 0.05)
				(type default)
			)
			(fill no)
			(layer "B.CrtYd")
		)
		(fp_line
			(start 0.504 0.25)
			(end 0.504 -0.248)
			(stroke
				(width 0.15)
				(type solid)
			)
			(layer "B.Fab")
		)
		(fp_line
			(start 0.504 -0.248)
			(end -0.494 -0.248)
			(stroke
				(width 0.15)
				(type solid)
			)
			(layer "B.Fab")
		)
		(fp_line
			(start -0.494 0.25)
			(end 0.504 0.25)
			(stroke
				(width 0.15)
				(type solid)
			)
			(layer "B.Fab")
		)
		(fp_line
			(start -0.494 -0.248)
			(end -0.494 0.25)
			(stroke
				(width 0.15)
				(type solid)
			)
			(layer "B.Fab")
		)
		(fp_text user "${REFERENCE}"
			(at -0.939 -4.599 0)
			(layer "B.Fab")
			(effects
				(font
					(size 0.7 0.7)
					(thickness 0.15)
				)
				(justify left bottom mirror)
			)
		)
		(fp_text user "License: Apache-2.0"
			(at -0.939 -5.799 0)
			(layer "B.Fab")
			(effects
				(font
					(size 0.7 0.7)
					(thickness 0.15)
				)
				(justify left bottom mirror)
			)
		)
		(fp_text user "Author: Antmicro"
			(at -0.939 -3.399 0)
			(layer "B.Fab")
			(effects
				(font
					(size 0.7 0.7)
					(thickness 0.15)
				)
				(justify left bottom mirror)
			)
		)
		(pad "1" smd roundrect
			(at -0.48 0 180)
			(size 0.59 0.64)
			(layers "B.Cu" "B.Mask" "B.Paste")
			(roundrect_rratio 0.25)
			(net 23 "GND")
			(pintype "passive")
		)
		(pad "2" smd roundrect
			(at 0.48 0 180)
			(size 0.59 0.64)
			(layers "B.Cu" "B.Mask" "B.Paste")
			(roundrect_rratio 0.25)
			(net 9 "VCCD")
			(pintype "passive")
		)
	)
	(footprint "antmicro-footprints:R_0402_1005Metric"
		(layer "B.Cu")
		(at 131.424999 125.900001 -90)
		(descr "Resistor SMD 0402")
		(tags "resistor SMD 0402")
		(property "Reference" "R66"
			(at -7.700002 -21.900002 90)
			(layer "B.SilkS")
			(effects
				(font
					(size 0.7 0.7)
					(thickness 0.15)
				)
				(justify mirror)
			)
		)
		(property "Value" "R_4k75_0.5%_0402"
			(at -1.011843 -1.772047 90)
			(layer "B.Fab")
			(effects
				(font
					(size 0.7 0.7)
					(thickness 0.15)
				)
				(justify left bottom mirror)
			)
		)
		(property "Datasheet" "https://industrial.panasonic.com/cdbs/www-data/pdf/RDQ0000/ast-ind-151033.pdf"
			(at 0 0 90)
			(layer "B.Fab")
			(hide yes)
			(effects
				(font
					(size 1.27 1.27)
					(thickness 0.15)
				)
				(justify mirror)
			)
		)
		(property "Description" "SMD Chip Resistor, 4.75 kohm, ± 0.5%, 100 mW, 0402 [1005 Metric], Thick Film, High Temperature"
			(at 0 0 90)
			(layer "B.Fab")
			(hide yes)
			(effects
				(font
					(size 1.27 1.27)
					(thickness 0.15)
				)
				(justify mirror)
			)
		)
		(property "MPN" "ERJ-H2RD4751X"
			(at 0 0 270)
			(unlocked yes)
			(layer "B.Fab")
			(hide yes)
			(effects
				(font
					(size 1 1)
					(thickness 0.15)
				)
				(justify mirror)
			)
		)
		(property "Manufacturer" "Panasonic"
			(at 0 0 270)
			(unlocked yes)
			(layer "B.Fab")
			(hide yes)
			(effects
				(font
					(size 1 1)
					(thickness 0.15)
				)
				(justify mirror)
			)
		)
		(property "License" "Apache-2.0"
			(at 0 0 270)
			(unlocked yes)
			(layer "B.Fab")
			(hide yes)
			(effects
				(font
					(size 1 1)
					(thickness 0.15)
				)
				(justify mirror)
			)
		)
		(property "Val" "4k75"
			(at 0 0 270)
			(unlocked yes)
			(layer "B.Fab")
			(hide yes)
			(effects
				(font
					(size 1 1)
					(thickness 0.15)
				)
				(justify mirror)
			)
		)
		(property "Tolerance" "0.5%"
			(at 0 0 270)
			(unlocked yes)
			(layer "B.Fab")
			(hide yes)
			(effects
				(font
					(size 1 1)
					(thickness 0.15)
				)
				(justify mirror)
			)
		)
		(property "Author" "Antmicro"
			(at 0 0 270)
			(unlocked yes)
			(layer "B.Fab")
			(hide yes)
			(effects
				(font
					(size 1 1)
					(thickness 0.15)
				)
				(justify mirror)
			)
		)
		(sheetname "/TB Controller/")
		(sheetfile "tb.kicad_sch")
		(attr smd)
		(fp_rect
			(start -0.925 0.47)
			(end 0.925 -0.47)
			(stroke
				(width 0.05)
				(type default)
			)
			(fill no)
			(layer "B.CrtYd")
		)
		(fp_rect
			(start -0.5 0.25)
			(end 0.5 -0.25)
			(stroke
				(width 0.15)
				(type solid)
			)
			(fill no)
			(layer "B.Fab")
		)
		(fp_text user "${REFERENCE}"
			(at -0.95 -3.168 90)
			(layer "B.Fab")
			(effects
				(font
					(size 0.7 0.7)
					(thickness 0.15)
				)
				(justify left bottom mirror)
			)
		)
		(fp_text user "Author: Antmicro"
			(at -0.95 -4.169 90)
			(layer "B.Fab")
			(effects
				(font
					(size 0.7 0.7)
					(thickness 0.15)
				)
				(justify left bottom mirror)
			)
		)
		(fp_text user "License: Apache-2.0"
			(at -0.95 -5.169 90)
			(layer "B.Fab")
			(effects
				(font
					(size 0.7 0.7)
					(thickness 0.15)
				)
				(justify left bottom mirror)
			)
		)
		(pad "1" smd roundrect
			(at -0.48 0 270)
			(size 0.59 0.64)
			(layers "B.Cu" "B.Mask" "B.Paste")
			(roundrect_rratio 0.25)
			(net 229 "Net-(U4D-RSENSE)")
			(pintype "passive")
		)
		(pad "2" smd roundrect
			(at 0.48 0 270)
			(size 0.59 0.64)
			(layers "B.Cu" "B.Mask" "B.Paste")
			(roundrect_rratio 0.25)
			(net 230 "Net-(U4D-RBIAS)")
			(pintype "passive")
		)
	)
)
